G04 ================== begin FILE IDENTIFICATION RECORD ==================*
G04 Layout Name:  9048_F0T_Management_Board_D_brd_V04_1213_1625.brd*
G04 Film Name:    outline*
G04 File Format:  Gerber RS274X*
G04 File Origin:  Cadence Allegro 17.2-S081*
G04 Origin Date:  Tue Dec 13 16:31:11 2022*
G04 *
G04 Layer:  BOARD GEOMETRY/DESIGN_OUTLINE*
G04 Layer:  BOARD GEOMETRY/CUTOUT*
G04 Layer:  BOARD GEOMETRY/OUTLINE*
G04 *
G04 Offset:    (0.00 0.00)*
G04 Mirror:    No*
G04 Mode:      Positive*
G04 Rotation:  0*
G04 FullContactRelief:  No*
G04 UndefLineWidth:     6.00*
G04 ================== end FILE IDENTIFICATION RECORD ====================*
%FSLAX25Y25*MOIN*%
%IR0*IPPOS*OFA0.00000B0.00000*MIA0B0*SFA1.00000B1.00000*%
%ADD10C,.006*%
G75*
%LPD*%
G75*
G54D10*
G01X7874Y450000D02*
G03X0Y442126I0J-7874D01*
G01Y335630D01*
G03X984Y334646I984J0D01*
G01X8858D01*
G02X10827Y332677I0J-1969D01*
G01Y322835D01*
G02X8858Y320866I-1969J0D01*
G01X984D01*
G03X0Y319882I0J-984D01*
G01Y7874D01*
G03X7874Y0I7874J0D01*
G01X346457D01*
G03X354331Y7874I0J7874D01*
G01Y319882D01*
G03X353346Y320866I-984J0D01*
G01X345472D01*
G02X343504Y322835I0J1968D01*
G01Y332677D01*
G02X345472Y334646I1968J0D01*
G01X353346D01*
G03X354331Y335630I1J984D01*
G01Y442126D01*
G03X346457Y450000I-7874J0D01*
G01X336614D01*
G02X334646Y451969I0J1969D01*
G01Y469024D01*
X331764Y474016D01*
X314921D01*
X311969Y471063D01*
Y451969D01*
G02X310000Y450000I-1969J0D01*
G01X304094D01*
G02X302126Y451969I1J1969D01*
G01Y471063D01*
X299173Y474016D01*
X265886D01*
X262933Y471063D01*
Y450886D01*
G02X254075I-4429J0D01*
G01Y471063D01*
X251122Y474016D01*
X184783D01*
X181831Y471063D01*
Y450098D01*
G02X174547I-3642J0D01*
G01Y471063D01*
X171594Y474016D01*
X138287D01*
X135335Y471063D01*
Y451870D01*
G02X124508I-5413J0D01*
G01Y471063D01*
X121555Y474016D01*
X55177D01*
X52224Y471063D01*
Y451969D01*
G02X50256Y450000I-1969J0D01*
G01X44350D01*
G02X42382Y451969I0J1969D01*
G01Y471063D01*
X39429Y474016D01*
X22567D01*
X19685Y469024D01*
Y451969D01*
G02X17717Y450000I-1969J0D01*
G01X7874D01*
G01X28346Y46417D02*
G02X15748I-6299J0D01*
G02X28346I6299J0D01*
G01X15748D02*
G02X28346I6299J0D01*
G02X15748I-6299J0D01*
G01D02*
G02X28346I6299J0D01*
G02X15748I-6299J0D01*
G01X30177Y89331D02*
G02X17854I-6161J0D01*
G02X30177I6162J0D01*
G01X17854D02*
G02X30177I6162J0D01*
G02X17854I-6161J0D01*
G01D02*
G02X30177I6162J0D01*
G02X17854I-6161J0D01*
G01X111614Y189721D02*
Y183422D01*
G02X99016I-6299J0D01*
G01Y189721D01*
G02X111614I6299J0D01*
G01X99016D02*
G02X111614I6299J0D01*
G01Y183422D01*
G02X99016I-6299J0D01*
G01Y189721D01*
G01D02*
Y183422D01*
G03X111614I6299J0D01*
G01Y189721D01*
G03X99016I-6299J0D01*
G01X97835Y213343D02*
G02X112795I7480J0D01*
G02X97835I-7480J0D01*
G01X112795D02*
G02X97835I-7480J0D01*
G02X112795I7480J0D01*
G01D02*
G03X97835I-7480J0D01*
G03X112795I7480J0D01*
G01X242913Y424016D02*
G02X229528I-6693J0D01*
G02X242913I6692J0D01*
G01X229528D02*
G02X242913I6692J0D01*
G02X229528I-6693J0D01*
G01D02*
G02X242913I6692J0D01*
G02X229528I-6693J0D01*
G01X307874D02*
G02X294488I-6693J0D01*
G02X307874I6693J0D01*
G01X294488D02*
G02X307874I6693J0D01*
G02X294488I-6693J0D01*
G01D02*
G02X307874I6693J0D01*
G02X294488I-6693J0D01*
G01X339764Y46417D02*
G02X327165I-6299J0D01*
G02X339764I6299J0D01*
G01X327165D02*
G02X339764I6299J0D01*
G02X327165I-6299J0D01*
G01D02*
G02X339764I6299J0D01*
G02X327165I-6299J0D01*
G01X336476Y89331D02*
G02X324154I-6161J0D01*
G02X336476I6161J0D01*
G01X324154D02*
G02X336476I6161J0D01*
G02X324154I-6161J0D01*
G01D02*
G02X336476I6161J0D01*
G02X324154I-6161J0D01*
M02*
